FILE_TYPE = CONNECTIVITY;
{Allegro Design Entry HDL 17.2-2016 S081 (4005846) 1/11/2022}
"PAGE_NUMBER" = 139;
0"NC";
END.
